(kicad_pcb
	(version 20260206)
	(generator "pcbnew")
	(generator_version "10.0")
	(general
		(thickness 1.6)
		(legacy_teardrops no)
	)
	(paper "A4")
	(title_block
		(title "baseboard — 13948-1b.1110WZS1818.brd")
		(comment 1 "Honey Badger (Wiwynn) / footprints 2439-2445 of 2523")
	)
	(layers
		(0 "F.Cu" signal "TOP")
		(4 "In1.Cu" signal "L2GND")
		(6 "In2.Cu" signal "L3")
		(8 "In3.Cu" signal "L4VCC")
		(10 "In4.Cu" signal "L5VCC")
		(12 "In5.Cu" signal "L6")
		(14 "In6.Cu" signal "L7GND")
		(2 "B.Cu" signal "BOTTOM")
		(9 "F.Adhes" user "F.Adhesive")
		(11 "B.Adhes" user "B.Adhesive")
		(13 "F.Paste" user "Package Geometry/Pastemask Top")
		(15 "B.Paste" user "Package Geometry/Pastemask Bottom")
		(5 "F.SilkS" user "Ref Des/Silkscreen Top")
		(7 "B.SilkS" user "Ref Des/Silkscreen Bottom")
		(1 "F.Mask" user "Board Geometry/Soldermask Top")
		(3 "B.Mask" user "Board Geometry/Soldermask Bottom")
		(17 "Dwgs.User" user "User.Drawings")
		(19 "Cmts.User" user "User.Comments")
		(21 "Eco1.User" user "User.Eco1")
		(23 "Eco2.User" user "User.Eco2")
		(25 "Edge.Cuts" user "Board Geometry/Outline")
		(27 "Margin" user)
		(31 "F.CrtYd" user "Package Geometry/Place Bound Top")
		(29 "B.CrtYd" user "Package Geometry/Place Bound Bottom")
		(35 "F.Fab" user "Ref Des/Assembly Top")
		(33 "B.Fab" user "Ref Des/Assembly Bottom")
	)
	(footprint ""
		(layer "B.Cu")
		(at 28.398216 -232.33888)
		(property "Reference" "R505"
			(at 0 0 0)
			(layer "B.SilkS")
			(hide yes)
			(effects
				(font
					(size 1.27 1.27)
				)
				(justify mirror)
			)
		)
		(property "Value" "0R2J-2-GP"
			(at -0.064008 -3.993896 0)
			(unlocked yes)
			(layer "B.Fab")
			(hide yes)
			(effects
				(font
					(size 1.016 1.016)
					(thickness 0.1524)
				)
				(justify mirror)
			)
		)
		(property "Device Type" "R402H16"
			(at -0.064008 -5.517896 0)
			(unlocked yes)
			(layer "B.Fab")
			(hide yes)
			(effects
				(font
					(size 1.016 1.016)
					(thickness 0.1524)
				)
				(justify mirror)
			)
		)
		(duplicate_pad_numbers_are_jumpers no)
		(fp_line
			(start -0.508 -0.9398)
			(end 0.508 -0.9398)
			(stroke
				(width 0.1524)
				(type default)
			)
			(layer "B.SilkS")
		)
		(fp_line
			(start 0.508 -0.9398)
			(end 0.508 0.9398)
			(stroke
				(width 0.1524)
				(type default)
			)
			(layer "B.SilkS")
		)
		(fp_rect
			(start 0.508 0.9398)
			(end -0.508 -0.9398)
			(stroke
				(width 0)
				(type default)
			)
			(fill no)
			(layer "B.CrtYd")
		)
		(fp_rect
			(start 0.508 0.9398)
			(end -0.508 -0.9398)
			(stroke
				(width 0)
				(type default)
			)
			(fill no)
			(layer "B.Fab")
		)
		(pad "1" smd custom
			(at 0 -0.4445 180)
			(size 0.1397 0.1397)
			(layers "B.Cu" "B.Mask" "B.Paste")
			(net "SAS_HDD_PWR3_PCIE")
			(options
				(clearance outline)
				(anchor circle)
			)
			(primitives
				(gr_poly
					(pts
						(arc
							(start -0.1778 0.2794)
							(mid -0.249642 0.249642)
							(end -0.2794 0.1778)
						)
						(arc
							(start -0.2794 -0.1778)
							(mid -0.249642 -0.249642)
							(end -0.1778 -0.2794)
						)
						(arc
							(start 0.1778 -0.2794)
							(mid 0.249642 -0.249642)
							(end 0.2794 -0.1778)
						)
						(arc
							(start 0.2794 0.1778)
							(mid 0.249642 0.249642)
							(end 0.1778 0.2794)
						)
					)
					(width 0)
					(fill yes)
				)
			)
		)
		(pad "2" smd custom
			(at 0 0.4445 180)
			(size 0.1397 0.1397)
			(layers "B.Cu" "B.Mask" "B.Paste")
			(net "SAS_HDD_PWR3")
			(options
				(clearance outline)
				(anchor circle)
			)
			(primitives
				(gr_poly
					(pts
						(arc
							(start -0.1778 0.2794)
							(mid -0.249642 0.249642)
							(end -0.2794 0.1778)
						)
						(arc
							(start -0.2794 -0.1778)
							(mid -0.249642 -0.249642)
							(end -0.1778 -0.2794)
						)
						(arc
							(start 0.1778 -0.2794)
							(mid 0.249642 -0.249642)
							(end 0.2794 -0.1778)
						)
						(arc
							(start 0.2794 0.1778)
							(mid 0.249642 0.249642)
							(end 0.1778 0.2794)
						)
					)
					(width 0)
					(fill yes)
				)
			)
		)
	)
	(footprint ""
		(layer "B.Cu")
		(at 338.713318 -133.353048 90)
		(property "Reference" "R551"
			(at 0 0 90)
			(layer "B.SilkS")
			(hide yes)
			(effects
				(font
					(size 1.27 1.27)
				)
				(justify mirror)
			)
		)
		(property "Value" "0R3J-0-U-GP"
			(at 0.0254 -2.5146 90)
			(unlocked yes)
			(layer "B.Fab")
			(hide yes)
			(effects
				(font
					(size 1.016 1.016)
					(thickness 0.1524)
				)
				(justify mirror)
			)
		)
		(property "Device Type" "R603H22"
			(at 0.0254 -4.0386 90)
			(unlocked yes)
			(layer "B.Fab")
			(hide yes)
			(effects
				(font
					(size 1.016 1.016)
					(thickness 0.1524)
				)
				(justify mirror)
			)
		)
		(duplicate_pad_numbers_are_jumpers no)
		(fp_line
			(start 0.4826 0)
			(end 0.2032 0)
			(stroke
				(width 0.2032)
				(type default)
			)
			(layer "B.SilkS")
		)
		(fp_line
			(start -0.2032 0)
			(end -0.4826 0)
			(stroke
				(width 0.2032)
				(type default)
			)
			(layer "B.SilkS")
		)
		(fp_rect
			(start 0.5842 1.3335)
			(end -0.5842 -1.3335)
			(stroke
				(width 0)
				(type default)
			)
			(fill no)
			(layer "B.CrtYd")
		)
		(fp_rect
			(start 0.5842 1.3335)
			(end -0.5842 -1.3335)
			(stroke
				(width 0)
				(type default)
			)
			(fill no)
			(layer "B.Fab")
		)
		(pad "1" smd custom
			(at 0 -0.762 270)
			(size 0.2159 0.2159)
			(layers "B.Cu" "B.Mask" "B.Paste")
			(net "USB_P0_DP_R")
			(options
				(clearance outline)
				(anchor circle)
			)
			(primitives
				(gr_poly
					(pts
						(arc
							(start -0.3302 0.4318)
							(mid -0.402042 0.402042)
							(end -0.4318 0.3302)
						)
						(arc
							(start -0.4318 -0.3302)
							(mid -0.402042 -0.402042)
							(end -0.3302 -0.4318)
						)
						(arc
							(start 0.3302 -0.4318)
							(mid 0.402042 -0.402042)
							(end 0.4318 -0.3302)
						)
						(arc
							(start 0.4318 0.3302)
							(mid 0.402042 0.402042)
							(end 0.3302 0.4318)
						)
					)
					(width 0)
					(fill yes)
				)
			)
		)
		(pad "2" smd custom
			(at 0 0.762 270)
			(size 0.2159 0.2159)
			(layers "B.Cu" "B.Mask" "B.Paste")
			(net "USB_P0_DP")
			(options
				(clearance outline)
				(anchor circle)
			)
			(primitives
				(gr_poly
					(pts
						(arc
							(start -0.3302 0.4318)
							(mid -0.402042 0.402042)
							(end -0.4318 0.3302)
						)
						(arc
							(start -0.4318 -0.3302)
							(mid -0.402042 -0.402042)
							(end -0.3302 -0.4318)
						)
						(arc
							(start 0.3302 -0.4318)
							(mid 0.402042 -0.402042)
							(end 0.4318 -0.3302)
						)
						(arc
							(start 0.4318 0.3302)
							(mid 0.402042 0.402042)
							(end 0.3302 0.4318)
						)
					)
					(width 0)
					(fill yes)
				)
			)
		)
	)
	(footprint ""
		(layer "B.Cu")
		(at 96.66097 -103.378 -90)
		(property "Reference" "STP80"
			(at 0 0 90)
			(layer "B.SilkS")
			(hide yes)
			(effects
				(font
					(size 1.27 1.27)
				)
				(justify mirror)
			)
		)
		(property "Value" "TPAD28"
			(at -0.0127 -1.8034 270)
			(unlocked yes)
			(layer "B.Fab")
			(hide yes)
			(effects
				(font
					(size 1.016 1.016)
					(thickness 0.1524)
				)
				(justify mirror)
			)
		)
		(property "Device Type" "TPAD28"
			(at -0.0127 -3.3274 270)
			(unlocked yes)
			(layer "B.Fab")
			(hide yes)
			(effects
				(font
					(size 1.016 1.016)
					(thickness 0.1524)
				)
				(justify mirror)
			)
		)
		(duplicate_pad_numbers_are_jumpers no)
		(fp_poly
			(pts
				(arc
					(start 0 -0.3556)
					(mid 0 0.3556)
					(end 0 -0.3556)
				)
			)
			(stroke
				(width 0)
				(type default)
			)
			(fill no)
			(layer "B.CrtYd")
		)
		(fp_poly
			(pts
				(arc
					(start 0 -0.6096)
					(mid 0 0.6096)
					(end 0 -0.6096)
				)
			)
			(stroke
				(width 0)
				(type default)
			)
			(fill no)
			(layer "B.Fab")
		)
		(pad "1" smd circle
			(at 0 0 90)
			(size 0.7112 0.7112)
			(layers "B.Cu" "B.Mask" "B.Paste")
			(net "EXP_TACH_IN0")
		)
	)
	(footprint ""
		(layer "B.Cu")
		(at 292.862 -164.211 180)
		(property "Reference" "R285"
			(at 0 0 0)
			(layer "B.SilkS")
			(hide yes)
			(effects
				(font
					(size 1.27 1.27)
				)
				(justify mirror)
			)
		)
		(property "Value" "0R2J-2-GP"
			(at -0.064008 -3.993896 180)
			(unlocked yes)
			(layer "B.Fab")
			(hide yes)
			(effects
				(font
					(size 1.016 1.016)
					(thickness 0.1524)
				)
				(justify mirror)
			)
		)
		(property "Device Type" "R402H16"
			(at -0.064008 -5.517896 180)
			(unlocked yes)
			(layer "B.Fab")
			(hide yes)
			(effects
				(font
					(size 1.016 1.016)
					(thickness 0.1524)
				)
				(justify mirror)
			)
		)
		(duplicate_pad_numbers_are_jumpers no)
		(fp_line
			(start 0.508 -0.9398)
			(end 0.508 0.9398)
			(stroke
				(width 0.1524)
				(type default)
			)
			(layer "B.SilkS")
		)
		(fp_line
			(start -0.508 -0.9398)
			(end 0.508 -0.9398)
			(stroke
				(width 0.1524)
				(type default)
			)
			(layer "B.SilkS")
		)
		(fp_rect
			(start 0.508 0.9398)
			(end -0.508 -0.9398)
			(stroke
				(width 0)
				(type default)
			)
			(fill no)
			(layer "B.CrtYd")
		)
		(fp_rect
			(start 0.508 0.9398)
			(end -0.508 -0.9398)
			(stroke
				(width 0)
				(type default)
			)
			(fill no)
			(layer "B.Fab")
		)
		(pad "1" smd custom
			(at 0 -0.4445)
			(size 0.1397 0.1397)
			(layers "B.Cu" "B.Mask" "B.Paste")
			(net "RMII_BMC_PHY_TXD1")
			(options
				(clearance outline)
				(anchor circle)
			)
			(primitives
				(gr_poly
					(pts
						(arc
							(start -0.1778 0.2794)
							(mid -0.249642 0.249642)
							(end -0.2794 0.1778)
						)
						(arc
							(start -0.2794 -0.1778)
							(mid -0.249642 -0.249642)
							(end -0.1778 -0.2794)
						)
						(arc
							(start 0.1778 -0.2794)
							(mid 0.249642 -0.249642)
							(end 0.2794 -0.1778)
						)
						(arc
							(start 0.2794 0.1778)
							(mid 0.249642 0.249642)
							(end 0.1778 0.2794)
						)
					)
					(width 0)
					(fill yes)
				)
			)
		)
		(pad "2" smd custom
			(at 0 0.4445)
			(size 0.1397 0.1397)
			(layers "B.Cu" "B.Mask" "B.Paste")
			(net "RMII0_BMC_C_PHY_TXD1")
			(options
				(clearance outline)
				(anchor circle)
			)
			(primitives
				(gr_poly
					(pts
						(arc
							(start -0.1778 0.2794)
							(mid -0.249642 0.249642)
							(end -0.2794 0.1778)
						)
						(arc
							(start -0.2794 -0.1778)
							(mid -0.249642 -0.249642)
							(end -0.1778 -0.2794)
						)
						(arc
							(start 0.1778 -0.2794)
							(mid 0.249642 -0.249642)
							(end 0.2794 -0.1778)
						)
						(arc
							(start 0.2794 0.1778)
							(mid 0.249642 0.249642)
							(end 0.1778 0.2794)
						)
					)
					(width 0)
					(fill yes)
				)
			)
		)
	)
	(footprint ""
		(layer "B.Cu")
		(at 197.739 -245.999 -90)
		(property "Reference" "R627"
			(at 0 0 90)
			(layer "B.SilkS")
			(hide yes)
			(effects
				(font
					(size 1.27 1.27)
				)
				(justify mirror)
			)
		)
		(property "Value" "10KR2F-2-GP"
			(at -0.064008 -3.993896 270)
			(unlocked yes)
			(layer "B.Fab")
			(hide yes)
			(effects
				(font
					(size 1.016 1.016)
					(thickness 0.1524)
				)
				(justify mirror)
			)
		)
		(property "Device Type" "R402H16"
			(at -0.064008 -5.517896 270)
			(unlocked yes)
			(layer "B.Fab")
			(hide yes)
			(effects
				(font
					(size 1.016 1.016)
					(thickness 0.1524)
				)
				(justify mirror)
			)
		)
		(duplicate_pad_numbers_are_jumpers no)
		(fp_line
			(start -0.508 -0.9398)
			(end 0.508 -0.9398)
			(stroke
				(width 0.1524)
				(type default)
			)
			(layer "B.SilkS")
		)
		(fp_line
			(start 0.508 -0.9398)
			(end 0.508 0.9398)
			(stroke
				(width 0.1524)
				(type default)
			)
			(layer "B.SilkS")
		)
		(fp_rect
			(start 0.508 0.9398)
			(end -0.508 -0.9398)
			(stroke
				(width 0)
				(type default)
			)
			(fill no)
			(layer "B.CrtYd")
		)
		(fp_rect
			(start 0.508 0.9398)
			(end -0.508 -0.9398)
			(stroke
				(width 0)
				(type default)
			)
			(fill no)
			(layer "B.Fab")
		)
		(pad "1" smd custom
			(at 0 -0.4445 90)
			(size 0.1397 0.1397)
			(layers "B.Cu" "B.Mask" "B.Paste")
			(net "PCIE_MATED#_B")
			(options
				(clearance outline)
				(anchor circle)
			)
			(primitives
				(gr_poly
					(pts
						(arc
							(start -0.1778 0.2794)
							(mid -0.249642 0.249642)
							(end -0.2794 0.1778)
						)
						(arc
							(start -0.2794 -0.1778)
							(mid -0.249642 -0.249642)
							(end -0.1778 -0.2794)
						)
						(arc
							(start 0.1778 -0.2794)
							(mid 0.249642 -0.249642)
							(end 0.2794 -0.1778)
						)
						(arc
							(start 0.2794 0.1778)
							(mid 0.249642 0.249642)
							(end 0.1778 0.2794)
						)
					)
					(width 0)
					(fill yes)
				)
			)
		)
		(pad "2" smd custom
			(at 0 0.4445 90)
			(size 0.1397 0.1397)
			(layers "B.Cu" "B.Mask" "B.Paste")
			(net "GND")
			(options
				(clearance outline)
				(anchor circle)
			)
			(primitives
				(gr_poly
					(pts
						(arc
							(start -0.1778 0.2794)
							(mid -0.249642 0.249642)
							(end -0.2794 0.1778)
						)
						(arc
							(start -0.2794 -0.1778)
							(mid -0.249642 -0.249642)
							(end -0.1778 -0.2794)
						)
						(arc
							(start 0.1778 -0.2794)
							(mid 0.249642 -0.249642)
							(end 0.2794 -0.1778)
						)
						(arc
							(start 0.2794 0.1778)
							(mid 0.249642 0.249642)
							(end 0.1778 0.2794)
						)
					)
					(width 0)
					(fill yes)
				)
			)
		)
	)
	(footprint ""
		(layer "B.Cu")
		(at 79.229966 -56.515 -90)
		(property "Reference" "SC925"
			(at 0 0 90)
			(layer "B.SilkS")
			(hide yes)
			(effects
				(font
					(size 1.27 1.27)
				)
				(justify mirror)
			)
		)
		(property "Value" "SC1U6D3V1MX-GP"
			(at -1.9177 2.0193 270)
			(unlocked yes)
			(layer "B.Fab")
			(hide yes)
			(effects
				(font
					(size 1.016 1.016)
					(thickness 0.1524)
				)
				(justify mirror)
			)
		)
		(property "Device Type" "C0201H14"
			(at -1.9177 0.4953 270)
			(unlocked yes)
			(layer "B.Fab")
			(hide yes)
			(effects
				(font
					(size 1.016 1.016)
					(thickness 0.1524)
				)
				(justify mirror)
			)
		)
		(duplicate_pad_numbers_are_jumpers no)
		(fp_rect
			(start 0.1524 0.3048)
			(end -0.1524 -0.3048)
			(stroke
				(width 0)
				(type default)
			)
			(fill no)
			(layer "B.CrtYd")
		)
		(fp_poly
			(pts
				(xy 0.2794 0.6477) (xy 0.2794 -0.6477) (xy -0.2794 -0.6477) (xy -0.2794 -0.1905) (xy -0.1524 -0.1905)
				(xy -0.1524 -0.3048) (xy 0.1524 -0.3048) (xy 0.1524 0.3048) (xy -0.1524 0.3048) (xy -0.1524 -0.1778)
				(xy -0.2794 -0.1778) (xy -0.2794 0.6477)
			)
			(stroke
				(width 0)
				(type default)
			)
			(fill no)
			(layer "B.CrtYd")
		)
		(fp_rect
			(start 0.2794 0.6477)
			(end -0.2794 -0.6477)
			(stroke
				(width 0)
				(type default)
			)
			(fill no)
			(layer "B.Fab")
		)
		(pad "1" smd custom
			(at 0 -0.2794 90)
			(size 0.0762 0.0762)
			(layers "B.Cu" "B.Mask" "B.Paste")
			(net "VDDA_SAS_REF_CLK")
			(options
				(clearance outline)
				(anchor circle)
			)
			(primitives
				(gr_poly
					(pts
						(arc
							(start 0.1524 0.127)
							(mid 0.137521 0.162921)
							(end 0.1016 0.1778)
						)
						(arc
							(start -0.1016 0.1778)
							(mid -0.137521 0.162921)
							(end -0.1524 0.127)
						)
						(arc
							(start -0.1524 -0.127)
							(mid -0.137521 -0.162921)
							(end -0.1016 -0.1778)
						)
						(arc
							(start 0.1016 -0.1778)
							(mid 0.137521 -0.162921)
							(end 0.1524 -0.127)
						)
					)
					(width 0)
					(fill yes)
				)
			)
		)
		(pad "2" smd custom
			(at 0 0.2794 90)
			(size 0.0762 0.0762)
			(layers "B.Cu" "B.Mask" "B.Paste")
			(net "GND")
			(options
				(clearance outline)
				(anchor circle)
			)
			(primitives
				(gr_poly
					(pts
						(arc
							(start 0.1524 0.127)
							(mid 0.137521 0.162921)
							(end 0.1016 0.1778)
						)
						(arc
							(start -0.1016 0.1778)
							(mid -0.137521 0.162921)
							(end -0.1524 0.127)
						)
						(arc
							(start -0.1524 -0.127)
							(mid -0.137521 -0.162921)
							(end -0.1016 -0.1778)
						)
						(arc
							(start 0.1016 -0.1778)
							(mid 0.137521 -0.162921)
							(end 0.1524 -0.127)
						)
					)
					(width 0)
					(fill yes)
				)
			)
		)
	)
	(footprint ""
		(layer "B.Cu")
		(at 267.716 -35.687 90)
		(property "Reference" "PR41"
			(at 0 0 90)
			(layer "B.SilkS")
			(hide yes)
			(effects
				(font
					(size 1.27 1.27)
				)
				(justify mirror)
			)
		)
		(property "Value" "3D01R5F-GP"
			(at 0 -8.9535 90)
			(unlocked yes)
			(layer "B.Fab")
			(hide yes)
			(effects
				(font
					(size 1.27 1.016)
					(thickness 0.1524)
				)
				(justify mirror)
			)
		)
		(property "Device Type" "R805H24"
			(at 0 -10.6299 90)
			(unlocked yes)
			(layer "B.Fab")
			(hide yes)
			(effects
				(font
					(size 1.27 1.016)
					(thickness 0.1524)
				)
				(justify mirror)
			)
		)
		(duplicate_pad_numbers_are_jumpers no)
		(fp_line
			(start 0.889 -1.7018)
			(end 0.889 0.2794)
			(stroke
				(width 0.1524)
				(type default)
			)
			(layer "B.SilkS")
		)
		(fp_line
			(start -0.889 -1.7018)
			(end 0.889 -1.7018)
			(stroke
				(width 0.1524)
				(type default)
			)
			(layer "B.SilkS")
		)
		(fp_line
			(start -0.889 -1.7018)
			(end -0.889 -0.381)
			(stroke
				(width 0.1524)
				(type default)
			)
			(layer "B.SilkS")
		)
		(fp_line
			(start 0.889 0.0762)
			(end 0.889 1.7018)
			(stroke
				(width 0.1524)
				(type default)
			)
			(layer "B.SilkS")
		)
		(fp_line
			(start 0.889 1.7018)
			(end -0.889 1.7018)
			(stroke
				(width 0.1524)
				(type default)
			)
			(layer "B.SilkS")
		)
		(fp_line
			(start -0.889 1.7018)
			(end -0.889 -0.508)
			(stroke
				(width 0.1524)
				(type default)
			)
			(layer "B.SilkS")
		)
		(fp_poly
			(pts
				(xy -0.9652 -1.778) (xy -0.9652 1.778) (xy 0.9652 1.778) (xy 0.9652 -1.778)
			)
			(stroke
				(width 0)
				(type default)
			)
			(fill no)
			(layer "B.CrtYd")
		)
		(fp_rect
			(start 0.9652 1.778)
			(end -0.9652 -1.778)
			(stroke
				(width 0)
				(type default)
			)
			(fill no)
			(layer "B.Fab")
		)
		(pad "1" smd rect
			(at 0 -0.9652 270)
			(size 1.397 1.143)
			(layers "B.Cu" "B.Mask" "B.Paste")
			(net "P1V8_STBY_VBST")
		)
		(pad "2" smd rect
			(at 0 0.9652 270)
			(size 1.397 1.143)
			(layers "B.Cu" "B.Mask" "B.Paste")
			(net "P1V8_STBY_VBST_RC")
		)
	)
)
